(kicad_pcb
	(version 20260206)
	(generator "pcbnew")
	(generator_version "10.0")
	(general
		(thickness 1.6)
		(legacy_teardrops no)
	)
	(paper "A4")
	(title_block
		(title "03242023_DA0F0TMBIJ0_F0T_Motherboard_J_brd_V01_OCP.brd")
		(comment 1 "Grand Teton / footprints 664-669 of 6105")
	)
	(layers
		(0 "F.Cu" signal "TOP")
		(4 "In1.Cu" signal "GND")
		(6 "In2.Cu" signal "IN1")
		(8 "In3.Cu" signal "GND1")
		(10 "In4.Cu" signal "IN2")
		(12 "In5.Cu" signal "GND2")
		(14 "In6.Cu" signal "IN3")
		(16 "In7.Cu" signal "GND3")
		(18 "In8.Cu" signal "VCC")
		(20 "In9.Cu" signal "VCC1")
		(22 "In10.Cu" signal "GND4")
		(24 "In11.Cu" signal "IN4")
		(26 "In12.Cu" signal "GND5")
		(28 "In13.Cu" signal "IN5")
		(30 "In14.Cu" signal "GND6")
		(32 "In15.Cu" signal "IN6")
		(34 "In16.Cu" signal "GND7")
		(2 "B.Cu" signal "BOTTOM")
		(9 "F.Adhes" user "F.Adhesive")
		(11 "B.Adhes" user "B.Adhesive")
		(13 "F.Paste" user "Package Geometry/Pastemask Top")
		(15 "B.Paste" user "Package Geometry/Pastemask Bottom")
		(5 "F.SilkS" user "Ref Des/Silkscreen Top")
		(7 "B.SilkS" user "Ref Des/Silkscreen Bottom")
		(1 "F.Mask" user "Board Geometry/Soldermask Top")
		(3 "B.Mask" user "Board Geometry/Soldermask Bottom")
		(17 "Dwgs.User" user "User.Drawings")
		(19 "Cmts.User" user "User.Comments")
		(21 "Eco1.User" user "User.Eco1")
		(23 "Eco2.User" user "User.Eco2")
		(25 "Edge.Cuts" user "Board Geometry/Outline")
		(27 "Margin" user)
		(31 "F.CrtYd" user "Package Geometry/Place Bound Top")
		(29 "B.CrtYd" user "Package Geometry/Place Bound Bottom")
		(35 "F.Fab" user "Ref Des/Assembly Top")
		(33 "B.Fab" user "Ref Des/Assembly Bottom")
	)
	(footprint ""
		(layer "F.Cu")
		(at 152.70988 -125.313948 90)
		(property "Reference" "U286"
			(at 2.012442 -5.37718 0)
			(unlocked yes)
			(layer "F.SilkS")
			(effects
				(font
					(size 0.7874 0.5842)
					(thickness 0.1524)
				)
				(justify left)
			)
		)
		(property "Value" ""
			(at 0 0 90)
			(layer "F.Fab")
			(effects
				(font
					(size 1.27 1.27)
				)
			)
		)
		(duplicate_pad_numbers_are_jumpers no)
		(fp_line
			(start 1.400048 -1.100074)
			(end -1.400048 -1.100074)
			(stroke
				(width 0.1524)
				(type default)
			)
			(layer "F.SilkS")
		)
		(fp_line
			(start 1.400048 -1.100074)
			(end 1.400048 1.100074)
			(stroke
				(width 0.1524)
				(type default)
			)
			(layer "F.SilkS")
		)
		(fp_line
			(start 1.400048 1.100074)
			(end -1.400048 1.100074)
			(stroke
				(width 0.1524)
				(type default)
			)
			(layer "F.SilkS")
		)
		(fp_line
			(start -1.400048 1.100074)
			(end -1.400048 -1.100074)
			(stroke
				(width 0.1524)
				(type default)
			)
			(layer "F.SilkS")
		)
		(fp_poly
			(pts
				(xy -0.686308 -1.26873) (xy -0.327152 -2.346452) (xy 0.39116 -1.627886)
			)
			(stroke
				(width 0)
				(type default)
			)
			(fill yes)
			(layer "F.SilkS")
		)
		(fp_line
			(start 0.674878 -1.100074)
			(end 0.674878 1.100074)
			(stroke
				(width 0.1)
				(type default)
			)
			(layer "F.Fab")
		)
		(fp_line
			(start -0.674878 -1.100074)
			(end 0.674878 -1.100074)
			(stroke
				(width 0.1)
				(type default)
			)
			(layer "F.Fab")
		)
		(fp_line
			(start 0.674878 1.100074)
			(end -0.674878 1.100074)
			(stroke
				(width 0.1)
				(type default)
			)
			(layer "F.Fab")
		)
		(fp_line
			(start -0.674878 1.100074)
			(end -0.674878 -1.100074)
			(stroke
				(width 0.1)
				(type default)
			)
			(layer "F.Fab")
		)
		(fp_poly
			(pts
				(xy -1.590548 -0.649986) (xy -2.606548 -1.157986) (xy -2.606548 -0.141986)
			)
			(stroke
				(width 0)
				(type default)
			)
			(fill yes)
			(layer "F.Fab")
		)
		(pad "1" smd rect
			(at -0.94996 -0.649986)
			(size 0.4318 0.6096)
			(layers "F.Cu" "F.Mask" "F.Paste")
			(net "OCP_V3_2_AUX_PWR_EN_R1")
		)
		(pad "2" smd rect
			(at -0.94996 0)
			(size 0.4318 0.6096)
			(layers "F.Cu" "F.Mask" "F.Paste")
			(net "FM_OCP_V3_2_PWR_GOOD")
		)
		(pad "3" smd rect
			(at -0.94996 0.649986)
			(size 0.4318 0.6096)
			(layers "F.Cu" "F.Mask" "F.Paste")
			(net "GND")
		)
		(pad "4" smd rect
			(at 0.94996 0.649986)
			(size 0.4318 0.6096)
			(layers "F.Cu" "F.Mask" "F.Paste")
			(net "FB_BMC_ISOLATE_R2")
		)
		(pad "5" smd rect
			(at 0.94996 -0.649986)
			(size 0.4318 0.6096)
			(layers "F.Cu" "F.Mask" "F.Paste")
			(net "P3V3_AUX")
		)
	)
	(footprint ""
		(layer "F.Cu")
		(at 9.277096 -100.017834 90)
		(property "Reference" "C2029"
			(at 0 0 90)
			(layer "F.SilkS")
			(hide yes)
			(effects
				(font
					(size 1.27 1.27)
				)
			)
		)
		(property "Value" ""
			(at 0 0 90)
			(layer "F.Fab")
			(effects
				(font
					(size 1.27 1.27)
				)
			)
		)
		(duplicate_pad_numbers_are_jumpers no)
		(fp_line
			(start 0.7874 -0.4064)
			(end 0.7874 0.4064)
			(stroke
				(width 0.1524)
				(type default)
			)
			(layer "F.SilkS")
		)
		(fp_line
			(start -0.7874 -0.4064)
			(end 0.7874 -0.4064)
			(stroke
				(width 0.1524)
				(type default)
			)
			(layer "F.SilkS")
		)
		(fp_line
			(start 0.7874 0.4064)
			(end -0.7874 0.4064)
			(stroke
				(width 0.1524)
				(type default)
			)
			(layer "F.SilkS")
		)
		(fp_line
			(start -0.7874 0.4064)
			(end -0.7874 -0.4064)
			(stroke
				(width 0.1524)
				(type default)
			)
			(layer "F.SilkS")
		)
		(fp_line
			(start -0.12065 -0.305054)
			(end -0.12065 -0.2794)
			(stroke
				(width 0.1)
				(type default)
			)
			(layer "F.Fab")
		)
		(fp_line
			(start -0.67945 -0.305054)
			(end -0.12065 -0.305054)
			(stroke
				(width 0.1)
				(type default)
			)
			(layer "F.Fab")
		)
		(fp_line
			(start 0.67945 -0.3048)
			(end 0.67945 0.3048)
			(stroke
				(width 0.1)
				(type default)
			)
			(layer "F.Fab")
		)
		(fp_line
			(start 0.12065 -0.3048)
			(end 0.67945 -0.3048)
			(stroke
				(width 0.1)
				(type default)
			)
			(layer "F.Fab")
		)
		(fp_line
			(start 0.12065 -0.2794)
			(end 0.12065 -0.3048)
			(stroke
				(width 0.1)
				(type default)
			)
			(layer "F.Fab")
		)
		(fp_line
			(start -0.12065 -0.2794)
			(end 0.12065 -0.2794)
			(stroke
				(width 0.1)
				(type default)
			)
			(layer "F.Fab")
		)
		(fp_line
			(start 0.120396 0.2794)
			(end -0.12065 0.2794)
			(stroke
				(width 0.1)
				(type default)
			)
			(layer "F.Fab")
		)
		(fp_line
			(start -0.12065 0.2794)
			(end -0.12065 0.3048)
			(stroke
				(width 0.1)
				(type default)
			)
			(layer "F.Fab")
		)
		(fp_line
			(start 0.67945 0.3048)
			(end 0.120396 0.3048)
			(stroke
				(width 0.1)
				(type default)
			)
			(layer "F.Fab")
		)
		(fp_line
			(start 0.120396 0.3048)
			(end 0.120396 0.2794)
			(stroke
				(width 0.1)
				(type default)
			)
			(layer "F.Fab")
		)
		(fp_line
			(start -0.12065 0.3048)
			(end -0.67945 0.3048)
			(stroke
				(width 0.1)
				(type default)
			)
			(layer "F.Fab")
		)
		(fp_line
			(start -0.67945 0.3048)
			(end -0.67945 -0.305054)
			(stroke
				(width 0.1)
				(type default)
			)
			(layer "F.Fab")
		)
		(pad "1" smd circle
			(at -0.40005 0 90)
			(size 0 0)
			(layers "F.Cu" "F.Mask" "F.Paste")
			(net "USB_HUB_XTAL_IN")
		)
		(pad "2" smd circle
			(at 0.40005 0 90)
			(size 0 0)
			(layers "F.Cu" "F.Mask" "F.Paste")
			(net "GND")
		)
	)
	(footprint ""
		(layer "F.Cu")
		(at 461.593946 -106.027728 180)
		(property "Reference" "R4752"
			(at 0 0 180)
			(layer "F.SilkS")
			(hide yes)
			(effects
				(font
					(size 1.27 1.27)
				)
			)
		)
		(property "Value" ""
			(at 0 0 180)
			(layer "F.Fab")
			(effects
				(font
					(size 1.27 1.27)
				)
			)
		)
		(duplicate_pad_numbers_are_jumpers no)
		(fp_line
			(start 0.7874 0.4064)
			(end -0.7874 0.4064)
			(stroke
				(width 0.1524)
				(type default)
			)
			(layer "F.SilkS")
		)
		(fp_line
			(start 0.7874 -0.4064)
			(end 0.7874 0.4064)
			(stroke
				(width 0.1524)
				(type default)
			)
			(layer "F.SilkS")
		)
		(fp_line
			(start -0.7874 0.4064)
			(end -0.7874 -0.4064)
			(stroke
				(width 0.1524)
				(type default)
			)
			(layer "F.SilkS")
		)
		(fp_line
			(start -0.7874 -0.4064)
			(end 0.7874 -0.4064)
			(stroke
				(width 0.1524)
				(type default)
			)
			(layer "F.SilkS")
		)
		(fp_line
			(start 0.67945 0.3048)
			(end 0.120396 0.3048)
			(stroke
				(width 0.1)
				(type default)
			)
			(layer "F.Fab")
		)
		(fp_line
			(start 0.67945 -0.3048)
			(end 0.67945 0.3048)
			(stroke
				(width 0.1)
				(type default)
			)
			(layer "F.Fab")
		)
		(fp_line
			(start 0.12065 -0.2794)
			(end 0.12065 -0.3048)
			(stroke
				(width 0.1)
				(type default)
			)
			(layer "F.Fab")
		)
		(fp_line
			(start 0.12065 -0.3048)
			(end 0.67945 -0.3048)
			(stroke
				(width 0.1)
				(type default)
			)
			(layer "F.Fab")
		)
		(fp_line
			(start 0.120396 0.3048)
			(end 0.120396 0.2794)
			(stroke
				(width 0.1)
				(type default)
			)
			(layer "F.Fab")
		)
		(fp_line
			(start 0.120396 0.2794)
			(end -0.12065 0.2794)
			(stroke
				(width 0.1)
				(type default)
			)
			(layer "F.Fab")
		)
		(fp_line
			(start -0.12065 0.3048)
			(end -0.67945 0.3048)
			(stroke
				(width 0.1)
				(type default)
			)
			(layer "F.Fab")
		)
		(fp_line
			(start -0.12065 0.2794)
			(end -0.12065 0.3048)
			(stroke
				(width 0.1)
				(type default)
			)
			(layer "F.Fab")
		)
		(fp_line
			(start -0.12065 -0.2794)
			(end 0.12065 -0.2794)
			(stroke
				(width 0.1)
				(type default)
			)
			(layer "F.Fab")
		)
		(fp_line
			(start -0.12065 -0.305054)
			(end -0.12065 -0.2794)
			(stroke
				(width 0.1)
				(type default)
			)
			(layer "F.Fab")
		)
		(fp_line
			(start -0.67945 0.3048)
			(end -0.67945 -0.305054)
			(stroke
				(width 0.1)
				(type default)
			)
			(layer "F.Fab")
		)
		(fp_line
			(start -0.67945 -0.305054)
			(end -0.12065 -0.305054)
			(stroke
				(width 0.1)
				(type default)
			)
			(layer "F.Fab")
		)
		(pad "1" smd circle
			(at -0.40005 0 180)
			(size 0 0)
			(layers "F.Cu" "F.Mask" "F.Paste")
			(net "HP_LVC3_OCP_V3_1_PRSNT2_N_R")
		)
		(pad "2" smd circle
			(at 0.40005 0 180)
			(size 0 0)
			(layers "F.Cu" "F.Mask" "F.Paste")
			(net "HP_LVC3_OCP_V3_1_PRSNT2_PLD_N")
		)
	)
	(footprint ""
		(layer "F.Cu")
		(at 215.95588 -32.857948 180)
		(property "Reference" "R3593"
			(at 0 0 180)
			(layer "F.SilkS")
			(hide yes)
			(effects
				(font
					(size 1.27 1.27)
				)
			)
		)
		(property "Value" ""
			(at 0 0 180)
			(layer "F.Fab")
			(effects
				(font
					(size 1.27 1.27)
				)
			)
		)
		(duplicate_pad_numbers_are_jumpers no)
		(fp_line
			(start 0.7874 0.4064)
			(end -0.7874 0.4064)
			(stroke
				(width 0.1524)
				(type default)
			)
			(layer "F.SilkS")
		)
		(fp_line
			(start 0.7874 -0.4064)
			(end 0.7874 0.4064)
			(stroke
				(width 0.1524)
				(type default)
			)
			(layer "F.SilkS")
		)
		(fp_line
			(start -0.7874 0.4064)
			(end -0.7874 -0.4064)
			(stroke
				(width 0.1524)
				(type default)
			)
			(layer "F.SilkS")
		)
		(fp_line
			(start -0.7874 -0.4064)
			(end 0.7874 -0.4064)
			(stroke
				(width 0.1524)
				(type default)
			)
			(layer "F.SilkS")
		)
		(fp_line
			(start 0.67945 0.3048)
			(end 0.120396 0.3048)
			(stroke
				(width 0.1)
				(type default)
			)
			(layer "F.Fab")
		)
		(fp_line
			(start 0.67945 -0.3048)
			(end 0.67945 0.3048)
			(stroke
				(width 0.1)
				(type default)
			)
			(layer "F.Fab")
		)
		(fp_line
			(start 0.12065 -0.2794)
			(end 0.12065 -0.3048)
			(stroke
				(width 0.1)
				(type default)
			)
			(layer "F.Fab")
		)
		(fp_line
			(start 0.12065 -0.3048)
			(end 0.67945 -0.3048)
			(stroke
				(width 0.1)
				(type default)
			)
			(layer "F.Fab")
		)
		(fp_line
			(start 0.120396 0.3048)
			(end 0.120396 0.2794)
			(stroke
				(width 0.1)
				(type default)
			)
			(layer "F.Fab")
		)
		(fp_line
			(start 0.120396 0.2794)
			(end -0.12065 0.2794)
			(stroke
				(width 0.1)
				(type default)
			)
			(layer "F.Fab")
		)
		(fp_line
			(start -0.12065 0.3048)
			(end -0.67945 0.3048)
			(stroke
				(width 0.1)
				(type default)
			)
			(layer "F.Fab")
		)
		(fp_line
			(start -0.12065 0.2794)
			(end -0.12065 0.3048)
			(stroke
				(width 0.1)
				(type default)
			)
			(layer "F.Fab")
		)
		(fp_line
			(start -0.12065 -0.2794)
			(end 0.12065 -0.2794)
			(stroke
				(width 0.1)
				(type default)
			)
			(layer "F.Fab")
		)
		(fp_line
			(start -0.12065 -0.305054)
			(end -0.12065 -0.2794)
			(stroke
				(width 0.1)
				(type default)
			)
			(layer "F.Fab")
		)
		(fp_line
			(start -0.67945 0.3048)
			(end -0.67945 -0.305054)
			(stroke
				(width 0.1)
				(type default)
			)
			(layer "F.Fab")
		)
		(fp_line
			(start -0.67945 -0.305054)
			(end -0.12065 -0.305054)
			(stroke
				(width 0.1)
				(type default)
			)
			(layer "F.Fab")
		)
		(pad "1" smd circle
			(at -0.40005 0 180)
			(size 0 0)
			(layers "F.Cu" "F.Mask" "F.Paste")
			(net "SMB_INA230_3V3AUX_SDA")
		)
		(pad "2" smd circle
			(at 0.40005 0 180)
			(size 0 0)
			(layers "F.Cu" "F.Mask" "F.Paste")
			(net "SMB_INA230_5_3V3AUX_SDA_R")
		)
	)
	(footprint ""
		(layer "F.Cu")
		(at 317.396622 -60.315348 180)
		(property "Reference" "R1478"
			(at 0 0 180)
			(layer "F.SilkS")
			(hide yes)
			(effects
				(font
					(size 1.27 1.27)
				)
			)
		)
		(property "Value" ""
			(at 0 0 180)
			(layer "F.Fab")
			(effects
				(font
					(size 1.27 1.27)
				)
			)
		)
		(duplicate_pad_numbers_are_jumpers no)
		(fp_line
			(start 0.7874 0.4064)
			(end -0.7874 0.4064)
			(stroke
				(width 0.1524)
				(type default)
			)
			(layer "F.SilkS")
		)
		(fp_line
			(start 0.7874 -0.4064)
			(end 0.7874 0.4064)
			(stroke
				(width 0.1524)
				(type default)
			)
			(layer "F.SilkS")
		)
		(fp_line
			(start -0.7874 0.4064)
			(end -0.7874 -0.4064)
			(stroke
				(width 0.1524)
				(type default)
			)
			(layer "F.SilkS")
		)
		(fp_line
			(start -0.7874 -0.4064)
			(end 0.7874 -0.4064)
			(stroke
				(width 0.1524)
				(type default)
			)
			(layer "F.SilkS")
		)
		(fp_line
			(start 0.67945 0.3048)
			(end 0.120396 0.3048)
			(stroke
				(width 0.1)
				(type default)
			)
			(layer "F.Fab")
		)
		(fp_line
			(start 0.67945 -0.3048)
			(end 0.67945 0.3048)
			(stroke
				(width 0.1)
				(type default)
			)
			(layer "F.Fab")
		)
		(fp_line
			(start 0.12065 -0.2794)
			(end 0.12065 -0.3048)
			(stroke
				(width 0.1)
				(type default)
			)
			(layer "F.Fab")
		)
		(fp_line
			(start 0.12065 -0.3048)
			(end 0.67945 -0.3048)
			(stroke
				(width 0.1)
				(type default)
			)
			(layer "F.Fab")
		)
		(fp_line
			(start 0.120396 0.3048)
			(end 0.120396 0.2794)
			(stroke
				(width 0.1)
				(type default)
			)
			(layer "F.Fab")
		)
		(fp_line
			(start 0.120396 0.2794)
			(end -0.12065 0.2794)
			(stroke
				(width 0.1)
				(type default)
			)
			(layer "F.Fab")
		)
		(fp_line
			(start -0.12065 0.3048)
			(end -0.67945 0.3048)
			(stroke
				(width 0.1)
				(type default)
			)
			(layer "F.Fab")
		)
		(fp_line
			(start -0.12065 0.2794)
			(end -0.12065 0.3048)
			(stroke
				(width 0.1)
				(type default)
			)
			(layer "F.Fab")
		)
		(fp_line
			(start -0.12065 -0.2794)
			(end 0.12065 -0.2794)
			(stroke
				(width 0.1)
				(type default)
			)
			(layer "F.Fab")
		)
		(fp_line
			(start -0.12065 -0.305054)
			(end -0.12065 -0.2794)
			(stroke
				(width 0.1)
				(type default)
			)
			(layer "F.Fab")
		)
		(fp_line
			(start -0.67945 0.3048)
			(end -0.67945 -0.305054)
			(stroke
				(width 0.1)
				(type default)
			)
			(layer "F.Fab")
		)
		(fp_line
			(start -0.67945 -0.305054)
			(end -0.12065 -0.305054)
			(stroke
				(width 0.1)
				(type default)
			)
			(layer "F.Fab")
		)
		(pad "1" smd circle
			(at -0.40005 0 180)
			(size 0 0)
			(layers "F.Cu" "F.Mask" "F.Paste")
			(net "FM_PCH_XTAL_INPUT_MODE_MGPIO_TE")
		)
		(pad "2" smd circle
			(at 0.40005 0 180)
			(size 0 0)
			(layers "F.Cu" "F.Mask" "F.Paste")
			(net "GND")
		)
	)
	(footprint ""
		(layer "F.Cu")
		(at 186.733942 -133.689598 -90)
		(property "Reference" "R4057"
			(at 0 0 270)
			(layer "F.SilkS")
			(hide yes)
			(effects
				(font
					(size 1.27 1.27)
				)
			)
		)
		(property "Value" ""
			(at 0 0 270)
			(layer "F.Fab")
			(effects
				(font
					(size 1.27 1.27)
				)
			)
		)
		(duplicate_pad_numbers_are_jumpers no)
		(fp_line
			(start -0.7874 0.4064)
			(end -0.7874 -0.4064)
			(stroke
				(width 0.1524)
				(type default)
			)
			(layer "F.SilkS")
		)
		(fp_line
			(start 0.7874 0.4064)
			(end -0.7874 0.4064)
			(stroke
				(width 0.1524)
				(type default)
			)
			(layer "F.SilkS")
		)
		(fp_line
			(start -0.7874 -0.4064)
			(end 0.7874 -0.4064)
			(stroke
				(width 0.1524)
				(type default)
			)
			(layer "F.SilkS")
		)
		(fp_line
			(start 0.7874 -0.4064)
			(end 0.7874 0.4064)
			(stroke
				(width 0.1524)
				(type default)
			)
			(layer "F.SilkS")
		)
		(fp_line
			(start -0.67945 0.3048)
			(end -0.67945 -0.305054)
			(stroke
				(width 0.1)
				(type default)
			)
			(layer "F.Fab")
		)
		(fp_line
			(start -0.12065 0.3048)
			(end -0.67945 0.3048)
			(stroke
				(width 0.1)
				(type default)
			)
			(layer "F.Fab")
		)
		(fp_line
			(start 0.120396 0.3048)
			(end 0.120396 0.2794)
			(stroke
				(width 0.1)
				(type default)
			)
			(layer "F.Fab")
		)
		(fp_line
			(start 0.67945 0.3048)
			(end 0.120396 0.3048)
			(stroke
				(width 0.1)
				(type default)
			)
			(layer "F.Fab")
		)
		(fp_line
			(start -0.12065 0.2794)
			(end -0.12065 0.3048)
			(stroke
				(width 0.1)
				(type default)
			)
			(layer "F.Fab")
		)
		(fp_line
			(start 0.120396 0.2794)
			(end -0.12065 0.2794)
			(stroke
				(width 0.1)
				(type default)
			)
			(layer "F.Fab")
		)
		(fp_line
			(start -0.12065 -0.2794)
			(end 0.12065 -0.2794)
			(stroke
				(width 0.1)
				(type default)
			)
			(layer "F.Fab")
		)
		(fp_line
			(start 0.12065 -0.2794)
			(end 0.12065 -0.3048)
			(stroke
				(width 0.1)
				(type default)
			)
			(layer "F.Fab")
		)
		(fp_line
			(start 0.12065 -0.3048)
			(end 0.67945 -0.3048)
			(stroke
				(width 0.1)
				(type default)
			)
			(layer "F.Fab")
		)
		(fp_line
			(start 0.67945 -0.3048)
			(end 0.67945 0.3048)
			(stroke
				(width 0.1)
				(type default)
			)
			(layer "F.Fab")
		)
		(fp_line
			(start -0.67945 -0.305054)
			(end -0.12065 -0.305054)
			(stroke
				(width 0.1)
				(type default)
			)
			(layer "F.Fab")
		)
		(fp_line
			(start -0.12065 -0.305054)
			(end -0.12065 -0.2794)
			(stroke
				(width 0.1)
				(type default)
			)
			(layer "F.Fab")
		)
		(pad "1" smd circle
			(at -0.40005 0 270)
			(size 0 0)
			(layers "F.Cu" "F.Mask" "F.Paste")
			(net "PRSNT_SWB_ISO_N")
		)
		(pad "2" smd circle
			(at 0.40005 0 270)
			(size 0 0)
			(layers "F.Cu" "F.Mask" "F.Paste")
			(net "PRSNT_SWB_ISO_R_N")
		)
	)
)
